FILE_TYPE = CONNECTIVITY;
{Allegro Design Entry HDL 17.2-2016 S081 (4005846) 1/11/2022}
"PAGE_NUMBER" = 93;
0"NC";
1"P3V3_AUX\g";
2"P12V_S3_AUX_CPU0_NVDIMM\g";
3"P12V_S3_AUX_CPU0_NVDIMM\g";
4"P3V3_AUX\g";
5"GND\g";
6"GND\g";
7"GND\g";
8"GND\g";
9"GND\g";
10"M_F_CPU0_SA_CB<7:0>";
11"M_F_CPU0_SB_CB<7:0>";
12"M_F_CPU0_SA_CA<6:0>";
13"M_F_CPU0_SB_CA<6:0>";
14"M_F_CPU0_SA_DQ<31:0>";
15"M_F_CPU0_SB_DQ<31:0>";
16"M_F_CPU0_SB_DQS_DP<9:0>";
17"M_F_CPU0_SA_DQS_DP<9:0>";
18"M_F_CPU0_SB_DQS_DN<9:0>";
19"M_F_CPU0_SA_DQS_DN<9:0>";
20"I3C_SPD_DDREFGH_CPU0_LVC1_SCL_R4";
21"I3C_SPD_DDREFGH_CPU0_LVC1_SDA";
22"M_F_CPU0_ALERT_N";
23"RST_M_EF_CPU0_FPGA_N";
24"PD_CHF_CPU0_DIMM2_SAA";
25"I3C_SPD_DDREFGH_CPU0_LVC1_SCL";
26"TP_CHF_CPU0_DIMM2_FRU_4";
27"TP_CHF_CPU0_DIMM2_FRU_5";
28"PWRGD_CHF_CPU0_DIMM2";
29"M_F_CPU0_SB_DQ<26>";
30"M_F_CPU0_SA_DQS_DN<9>";
31"M_F_CPU0_SA_DQS_DN<8>";
32"M_F_CPU0_SA_DQS_DN<7>";
33"M_F_CPU0_SA_DQS_DN<6>";
34"M_F_CPU0_SA_DQS_DN<5>";
35"M_F_CPU0_SA_DQS_DN<4>";
36"M_F_CPU0_SA_DQS_DN<3>";
37"M_F_CPU0_SA_DQS_DN<2>";
38"M_F_CPU0_SA_DQS_DN<0>";
39"M_F_CPU0_SA_DQS_DN<1>";
40"M_F_CPU0_SB_DQS_DN<8>";
41"M_F_CPU0_SB_DQS_DN<9>";
42"M_F_CPU0_SB_DQS_DN<7>";
43"M_F_CPU0_SB_DQS_DN<6>";
44"M_F_CPU0_SB_DQS_DN<5>";
45"M_F_CPU0_SB_DQS_DN<4>";
46"M_F_CPU0_SB_DQS_DN<3>";
47"M_F_CPU0_SB_DQS_DN<2>";
48"M_F_CPU0_SB_DQS_DN<0>";
49"M_F_CPU0_SB_DQS_DN<1>";
50"M_F_CPU0_SA_DQS_DP<6>";
51"M_F_CPU0_SA_DQS_DP<8>";
52"M_F_CPU0_SA_DQS_DP<7>";
53"M_F_CPU0_SA_DQS_DP<9>";
54"M_F_CPU0_SA_DQS_DP<1>";
55"M_F_CPU0_SA_DQS_DP<3>";
56"M_F_CPU0_SA_DQS_DP<2>";
57"M_F_CPU0_SA_DQS_DP<4>";
58"M_F_CPU0_SA_DQS_DP<5>";
59"M_F_CPU0_SB_DQS_DP<6>";
60"M_F_CPU0_SB_DQS_DP<7>";
61"M_F_CPU0_SB_DQS_DP<8>";
62"M_F_CPU0_SA_DQS_DP<0>";
63"M_F_CPU0_SB_DQS_DP<9>";
64"M_F_CPU0_SB_DQS_DP<1>";
65"M_F_CPU0_SB_DQS_DP<3>";
66"M_F_CPU0_SB_DQS_DP<2>";
67"M_F_CPU0_SB_DQS_DP<4>";
68"M_F_CPU0_SB_DQS_DP<5>";
69"M_F_CPU0_SB_DQS_DP<0>";
70"M_F_CPU0_SA_DQ<31>";
71"M_F_CPU0_SA_DQ<30>";
72"M_F_CPU0_SB_DQ<31>";
73"M_F_CPU0_SA_CB<1>";
74"M_F_CPU0_SB_DQ<10>";
75"M_F_CPU0_SA_DQ<8>";
76"M_F_CPU0_SA_DQ<7>";
77"TP_CHF_CPU0_DIMM2_FRU_0";
78"TP_CHF_CPU0_DIMM2_FRU_1";
79"TP_CHF_CPU0_DIMM2_FRU_2";
80"TP_CHF_CPU0_DIMM2_FRU_3";
81"TP_CHF_CPU0_DIMM2_FRU_6";
82"M_F_CPU0_SB_PAR";
83"M_F_CPU0_SA_PAR";
84"M_F_CPU0_SB_RSP<1>";
85"M_F_CPU0_SA_RSP<1>";
86"M_F_CPU0_SB_DQ<0>";
87"M_F_CPU0_SB_DQ<1>";
88"M_F_CPU0_SB_DQ<2>";
89"M_F_CPU0_SB_DQ<3>";
90"M_F_CPU0_SB_DQ<4>";
91"M_F_CPU0_SB_DQ<5>";
92"M_F_CPU0_SB_DQ<6>";
93"M_F_CPU0_SB_DQ<7>";
94"M_F_CPU0_SB_DQ<8>";
95"M_F_CPU0_SB_DQ<9>";
96"M_F_CPU0_SB_DQ<11>";
97"M_F_CPU0_SB_DQ<12>";
98"M_F_CPU0_SB_DQ<13>";
99"M_F_CPU0_SB_DQ<14>";
100"M_F_CPU0_SB_DQ<15>";
101"M_F_CPU0_SB_DQ<16>";
102"M_F_CPU0_SB_DQ<17>";
103"M_F_CPU0_SB_DQ<18>";
104"M_F_CPU0_SB_DQ<19>";
105"M_F_CPU0_SB_DQ<20>";
106"M_F_CPU0_SB_DQ<21>";
107"M_F_CPU0_SB_DQ<22>";
108"M_F_CPU0_SB_DQ<23>";
109"M_F_CPU0_SB_DQ<24>";
110"M_F_CPU0_SB_DQ<25>";
111"M_F_CPU0_SB_DQ<27>";
112"M_F_CPU0_SB_DQ<28>";
113"M_F_CPU0_SB_DQ<29>";
114"M_F_CPU0_SB_DQ<30>";
115"M_F_CPU0_SA_DQ<0>";
116"M_F_CPU0_SA_DQ<1>";
117"M_F_CPU0_SA_DQ<2>";
118"M_F_CPU0_SA_DQ<3>";
119"M_F_CPU0_SA_DQ<4>";
120"M_F_CPU0_SA_DQ<5>";
121"M_F_CPU0_SA_DQ<6>";
122"M_F_CPU0_SA_DQ<9>";
123"M_F_CPU0_SA_DQ<10>";
124"M_F_CPU0_SA_DQ<11>";
125"M_F_CPU0_SA_DQ<12>";
126"M_F_CPU0_SA_DQ<13>";
127"M_F_CPU0_SA_DQ<14>";
128"M_F_CPU0_SA_DQ<15>";
129"M_F_CPU0_SA_DQ<16>";
130"M_F_CPU0_SA_DQ<17>";
131"M_F_CPU0_SA_DQ<18>";
132"M_F_CPU0_SA_DQ<19>";
133"M_F_CPU0_SA_DQ<20>";
134"M_F_CPU0_SA_DQ<21>";
135"M_F_CPU0_SA_DQ<22>";
136"M_F_CPU0_SA_DQ<23>";
137"M_F_CPU0_SA_DQ<24>";
138"M_F_CPU0_SA_DQ<25>";
139"M_F_CPU0_SA_DQ<26>";
140"M_F_CPU0_SA_DQ<27>";
141"M_F_CPU0_SA_DQ<28>";
142"M_F_CPU0_SA_DQ<29>";
143"M_F_CPU0_SB_CS_N<3>";
144"M_F_CPU0_SA_CS_N<3>";
145"M_F_CPU0_SB_CS_N<2>";
146"M_F_CPU0_SA_CS_N<2>";
147"M_F_CPU0_CLK_DP<1>";
148"M_F_CPU0_CLK_DN<1>";
149"M_F_CPU0_SB_CB<0>";
150"M_F_CPU0_SB_CB<1>";
151"M_F_CPU0_SB_CB<2>";
152"M_F_CPU0_SB_CB<3>";
153"M_F_CPU0_SB_CB<4>";
154"M_F_CPU0_SB_CB<5>";
155"M_F_CPU0_SB_CB<6>";
156"M_F_CPU0_SA_CB<0>";
157"M_F_CPU0_SA_CB<2>";
158"M_F_CPU0_SA_CB<3>";
159"M_F_CPU0_SA_CB<5>";
160"M_F_CPU0_SA_CB<6>";
161"M_F_CPU0_SB_CA<6>";
162"M_F_CPU0_SA_CA<6>";
163"M_F_CPU0_SB_CA<5>";
164"M_F_CPU0_SA_CA<5>";
165"M_F_CPU0_SB_CA<4>";
166"M_F_CPU0_SA_CA<4>";
167"M_F_CPU0_SB_CA<3>";
168"M_F_CPU0_SA_CA<3>";
169"M_F_CPU0_SB_CA<2>";
170"M_F_CPU0_SA_CA<2>";
171"M_F_CPU0_SB_CA<1>";
172"M_F_CPU0_SA_CA<1>";
173"M_F_CPU0_SB_CA<0>";
174"M_F_CPU0_SA_CA<0>";
175"M_F_CPU0_SB_CB<7>";
176"M_F_CPU0_SA_CB<4>";
177"M_F_CPU0_SA_CB<7>";
178"PD_CHF_CPU0_DIMM2_SAA";
%"UNIVERSAL_GND"
"1","(-1850,50)","0","logical_power","I1";
;
CDS_LIB"logical_power"
HDL_POWER"GND";
"A"9;
%"TAP"
"1","(-425,3525)","0","standard","I100";
;
CDS_LIB"standard"
BODY_TYPE"PLUMBING"
HDL_TAP"TRUE";
"B \NAC \NWC"14;
"S \NAC"
BN"13"126;
%"TAP"
"1","(-425,3575)","0","standard","I101";
;
CDS_LIB"standard"
BODY_TYPE"PLUMBING"
HDL_TAP"TRUE";
"B \NAC \NWC"14;
"S \NAC"
BN"14"127;
%"TAP"
"1","(-425,3725)","0","standard","I102";
;
CDS_LIB"standard"
BODY_TYPE"PLUMBING"
HDL_TAP"TRUE";
"B \NAC \NWC"14;
"S \NAC"
BN"17"130;
%"TAP"
"1","(-425,3775)","0","standard","I103";
;
CDS_LIB"standard"
BODY_TYPE"PLUMBING"
HDL_TAP"TRUE";
"B \NAC \NWC"14;
"S \NAC"
BN"18"131;
%"TAP"
"1","(-425,3825)","0","standard","I104";
;
CDS_LIB"standard"
BODY_TYPE"PLUMBING"
HDL_TAP"TRUE";
"B \NAC \NWC"14;
"S \NAC"
BN"19"132;
%"TAP"
"1","(-425,3875)","0","standard","I105";
;
CDS_LIB"standard"
BODY_TYPE"PLUMBING"
HDL_TAP"TRUE";
"B \NAC \NWC"14;
"S \NAC"
BN"20"133;
%"TAP"
"1","(-425,3675)","0","standard","I106";
;
CDS_LIB"standard"
BODY_TYPE"PLUMBING"
HDL_TAP"TRUE";
"B \NAC \NWC"14;
"S \NAC"
BN"16"129;
%"TAP"
"1","(-425,3925)","0","standard","I107";
;
CDS_LIB"standard"
BODY_TYPE"PLUMBING"
HDL_TAP"TRUE";
"B \NAC \NWC"14;
"S \NAC"
BN"21"134;
%"TAP"
"1","(-425,3975)","0","standard","I108";
;
CDS_LIB"standard"
BODY_TYPE"PLUMBING"
HDL_TAP"TRUE";
"B \NAC \NWC"14;
"S \NAC"
BN"22"135;
%"TAP"
"1","(-425,4025)","0","standard","I109";
;
CDS_LIB"standard"
BODY_TYPE"PLUMBING"
HDL_TAP"TRUE";
"B \NAC \NWC"14;
"S \NAC"
BN"23"136;
%"TAP"
"1","(-425,4125)","0","standard","I110";
;
CDS_LIB"standard"
BODY_TYPE"PLUMBING"
HDL_TAP"TRUE";
"B \NAC \NWC"14;
"S \NAC"
BN"25"138;
%"TAP"
"1","(-425,4075)","0","standard","I111";
;
CDS_LIB"standard"
BODY_TYPE"PLUMBING"
HDL_TAP"TRUE";
"B \NAC \NWC"14;
"S \NAC"
BN"24"137;
%"TAP"
"1","(-425,4175)","0","standard","I112";
;
CDS_LIB"standard"
BODY_TYPE"PLUMBING"
HDL_TAP"TRUE";
"B \NAC \NWC"14;
"S \NAC"
BN"26"139;
%"TAP"
"1","(-425,4225)","0","standard","I113";
;
CDS_LIB"standard"
BODY_TYPE"PLUMBING"
HDL_TAP"TRUE";
"B \NAC \NWC"14;
"S \NAC"
BN"27"140;
%"TAP"
"1","(-425,4275)","0","standard","I114";
;
CDS_LIB"standard"
BODY_TYPE"PLUMBING"
HDL_TAP"TRUE";
"B \NAC \NWC"14;
"S \NAC"
BN"28"141;
%"TAP"
"1","(-425,4375)","0","standard","I115";
;
CDS_LIB"standard"
BODY_TYPE"PLUMBING"
HDL_TAP"TRUE";
"B \NAC \NWC"14;
"S \NAC"
BN"30"71;
%"TAP"
"1","(-425,4325)","0","standard","I116";
;
CDS_LIB"standard"
BODY_TYPE"PLUMBING"
HDL_TAP"TRUE";
"B \NAC \NWC"14;
"S \NAC"
BN"29"142;
%"TAP"
"1","(-2075,4425)","2","standard","I118";
;
CDS_LIB"standard"
BODY_TYPE"PLUMBING"
HDL_TAP"TRUE";
"B \NAC \NWC"12;
"S \NAC"
BN"6"162;
%"TAP"
"1","(-425,4425)","0","standard","I119";
;
CDS_LIB"standard"
BODY_TYPE"PLUMBING"
HDL_TAP"TRUE";
"B \NAC \NWC"14;
"S \NAC"
BN"31"70;
%"VCC_CORE"
"1","(-2900,2300)","0","logical_power","I12";
;
HDL_POWER"P3V3_AUX"
CDS_LIB"logical_power";
"A"1;
%"UNIVERSAL_GND"
"1","(1300,175)","0","logical_power","I120";
;
CDS_LIB"logical_power"
HDL_POWER"GND";
"A"8;
%"UNIVERSAL_GND"
"1","(2925,175)","0","logical_power","I121";
;
CDS_LIB"logical_power"
HDL_POWER"GND";
"A"7;
%"Q_CAP"
"1","(1300,550)","0","pure_quanta","I122";
;
PART_NUMBER"CH5221MEB00"
TOLERANCE"20%"
PACK_TYPE"C0402"
MATERIAL"X6S"
VOLTAGE"6.3V"
VALUE"2.2UF"
$LOCATION"C35"
CDS_LIB"pure_quanta"
CDS_LOCATION"C35"
$SEC"1"
CDS_SEC"1";
"B"
$PN"2"8;
"A"
$PN"1"4;
%"VCC_CORE"
"1","(1300,875)","0","logical_power","I123";
;
HDL_POWER"P3V3_AUX"
CDS_LIB"logical_power";
"A"4;
%"Q_CAP"
"1","(2300,550)","0","pure_quanta","I126";
;
PART_NUMBER"CH6103KEA00"
TOLERANCE"10%"
VOLTAGE"16V"
VALUE"10UF"
MATERIAL"X6S"
PACK_TYPE"C0805"
$LOCATION"C36"
CDS_LIB"pure_quanta"
CDS_LOCATION"C36"
$SEC"1"
CDS_SEC"1";
"B"
$PN"2"7;
"A"
$PN"1"3;
%"VCC_CORE"
"1","(2300,875)","0","logical_power","I127";
;
HDL_POWER"P12V_S3_AUX_CPU0_NVDIMM"
CDS_LIB"logical_power";
"A"3;
%"Q_CAP"
"1","(2925,550)","0","pure_quanta","I128";
;
PART_NUMBER"CH6103KEA00"
PACK_TYPE"C0805"
VALUE"10UF"
VOLTAGE"16V"
TOLERANCE"10%"
MATERIAL"X6S"
$LOCATION"C37"
CDS_LIB"pure_quanta"
CDS_LOCATION"C37"
$SEC"1"
CDS_SEC"1";
"B"
$PN"2"7;
"A"
$PN"1"3;
%"TAP"
"1","(2325,2475)","0","standard","I129";
;
CDS_LIB"standard"
BODY_TYPE"PLUMBING"
HDL_TAP"TRUE";
"B \NAC \NWC"16;
"S \NAC"
BN"0"69;
%"TAP"
"1","(2325,2575)","0","standard","I130";
;
CDS_LIB"standard"
BODY_TYPE"PLUMBING"
HDL_TAP"TRUE";
"B \NAC \NWC"16;
"S \NAC"
BN"1"64;
%"TAP"
"1","(2325,2775)","0","standard","I131";
;
CDS_LIB"standard"
BODY_TYPE"PLUMBING"
HDL_TAP"TRUE";
"B \NAC \NWC"16;
"S \NAC"
BN"3"65;
%"TAP"
"1","(2325,2675)","0","standard","I132";
;
CDS_LIB"standard"
BODY_TYPE"PLUMBING"
HDL_TAP"TRUE";
"B \NAC \NWC"16;
"S \NAC"
BN"2"66;
%"TAP"
"1","(2325,2875)","0","standard","I133";
;
CDS_LIB"standard"
BODY_TYPE"PLUMBING"
HDL_TAP"TRUE";
"B \NAC \NWC"16;
"S \NAC"
BN"4"67;
%"TAP"
"1","(2325,2975)","0","standard","I134";
;
CDS_LIB"standard"
BODY_TYPE"PLUMBING"
HDL_TAP"TRUE";
"B \NAC \NWC"16;
"S \NAC"
BN"5"68;
%"TAP"
"1","(2325,3075)","0","standard","I135";
;
CDS_LIB"standard"
BODY_TYPE"PLUMBING"
HDL_TAP"TRUE";
"B \NAC \NWC"16;
"S \NAC"
BN"6"59;
%"TAP"
"1","(2325,3175)","0","standard","I136";
;
CDS_LIB"standard"
BODY_TYPE"PLUMBING"
HDL_TAP"TRUE";
"B \NAC \NWC"16;
"S \NAC"
BN"7"60;
%"TAP"
"1","(2325,3275)","0","standard","I137";
;
CDS_LIB"standard"
BODY_TYPE"PLUMBING"
HDL_TAP"TRUE";
"B \NAC \NWC"16;
"S \NAC"
BN"8"61;
%"TAP"
"1","(2500,2425)","0","standard","I138";
;
CDS_LIB"standard"
BODY_TYPE"PLUMBING"
HDL_TAP"TRUE";
"B \NAC \NWC"18;
"S \NAC"
BN"0"48;
%"TAP"
"1","(2500,2525)","0","standard","I139";
;
CDS_LIB"standard"
BODY_TYPE"PLUMBING"
HDL_TAP"TRUE";
"B \NAC \NWC"18;
"S \NAC"
BN"1"49;
%"TAP"
"1","(2500,2725)","0","standard","I140";
;
CDS_LIB"standard"
BODY_TYPE"PLUMBING"
HDL_TAP"TRUE";
"B \NAC \NWC"18;
"S \NAC"
BN"3"46;
%"TAP"
"1","(2500,2625)","0","standard","I141";
;
CDS_LIB"standard"
BODY_TYPE"PLUMBING"
HDL_TAP"TRUE";
"B \NAC \NWC"18;
"S \NAC"
BN"2"47;
%"TAP"
"1","(2500,2825)","0","standard","I142";
;
CDS_LIB"standard"
BODY_TYPE"PLUMBING"
HDL_TAP"TRUE";
"B \NAC \NWC"18;
"S \NAC"
BN"4"45;
%"TAP"
"1","(2500,2925)","0","standard","I143";
;
CDS_LIB"standard"
BODY_TYPE"PLUMBING"
HDL_TAP"TRUE";
"B \NAC \NWC"18;
"S \NAC"
BN"5"44;
%"TAP"
"1","(2500,3025)","0","standard","I144";
;
CDS_LIB"standard"
BODY_TYPE"PLUMBING"
HDL_TAP"TRUE";
"B \NAC \NWC"18;
"S \NAC"
BN"6"43;
%"TAP"
"1","(2500,3225)","0","standard","I145";
;
CDS_LIB"standard"
BODY_TYPE"PLUMBING"
HDL_TAP"TRUE";
"B \NAC \NWC"18;
"S \NAC"
BN"8"40;
%"TAP"
"1","(2500,3125)","0","standard","I146";
;
CDS_LIB"standard"
BODY_TYPE"PLUMBING"
HDL_TAP"TRUE";
"B \NAC \NWC"18;
"S \NAC"
BN"7"42;
%"TAP"
"1","(2500,3325)","0","standard","I147";
;
CDS_LIB"standard"
BODY_TYPE"PLUMBING"
HDL_TAP"TRUE";
"B \NAC \NWC"18;
"S \NAC"
BN"9"41;
%"TAP"
"1","(2325,3525)","0","standard","I148";
;
CDS_LIB"standard"
BODY_TYPE"PLUMBING"
HDL_TAP"TRUE";
"B \NAC \NWC"17;
"S \NAC"
BN"0"62;
%"TAP"
"1","(2325,3375)","0","standard","I149";
;
CDS_LIB"standard"
BODY_TYPE"PLUMBING"
HDL_TAP"TRUE";
"B \NAC \NWC"16;
"S \NAC"
BN"9"63;
%"TAP"
"1","(2325,3625)","0","standard","I150";
;
CDS_LIB"standard"
BODY_TYPE"PLUMBING"
HDL_TAP"TRUE";
"B \NAC \NWC"17;
"S \NAC"
BN"1"54;
%"TAP"
"1","(2325,3825)","0","standard","I151";
;
CDS_LIB"standard"
BODY_TYPE"PLUMBING"
HDL_TAP"TRUE";
"B \NAC \NWC"17;
"S \NAC"
BN"3"55;
%"TAP"
"1","(2325,3725)","0","standard","I152";
;
CDS_LIB"standard"
BODY_TYPE"PLUMBING"
HDL_TAP"TRUE";
"B \NAC \NWC"17;
"S \NAC"
BN"2"56;
%"TAP"
"1","(2325,3925)","0","standard","I153";
;
CDS_LIB"standard"
BODY_TYPE"PLUMBING"
HDL_TAP"TRUE";
"B \NAC \NWC"17;
"S \NAC"
BN"4"57;
%"TAP"
"1","(2325,4025)","0","standard","I154";
;
CDS_LIB"standard"
BODY_TYPE"PLUMBING"
HDL_TAP"TRUE";
"B \NAC \NWC"17;
"S \NAC"
BN"5"58;
%"TAP"
"1","(2325,4125)","0","standard","I155";
;
CDS_LIB"standard"
BODY_TYPE"PLUMBING"
HDL_TAP"TRUE";
"B \NAC \NWC"17;
"S \NAC"
BN"6"50;
%"TAP"
"1","(2325,4325)","0","standard","I156";
;
CDS_LIB"standard"
BODY_TYPE"PLUMBING"
HDL_TAP"TRUE";
"B \NAC \NWC"17;
"S \NAC"
BN"8"51;
%"TAP"
"1","(2325,4225)","0","standard","I157";
;
CDS_LIB"standard"
BODY_TYPE"PLUMBING"
HDL_TAP"TRUE";
"B \NAC \NWC"17;
"S \NAC"
BN"7"52;
%"TAP"
"1","(2500,3475)","0","standard","I158";
;
CDS_LIB"standard"
BODY_TYPE"PLUMBING"
HDL_TAP"TRUE";
"B \NAC \NWC"19;
"S \NAC"
BN"0"38;
%"TAP"
"1","(2500,3575)","0","standard","I159";
;
CDS_LIB"standard"
BODY_TYPE"PLUMBING"
HDL_TAP"TRUE";
"B \NAC \NWC"19;
"S \NAC"
BN"1"39;
%"TAP"
"1","(2500,3675)","0","standard","I160";
;
CDS_LIB"standard"
BODY_TYPE"PLUMBING"
HDL_TAP"TRUE";
"B \NAC \NWC"19;
"S \NAC"
BN"2"37;
%"TAP"
"1","(2500,3875)","0","standard","I161";
;
CDS_LIB"standard"
BODY_TYPE"PLUMBING"
HDL_TAP"TRUE";
"B \NAC \NWC"19;
"S \NAC"
BN"4"35;
%"TAP"
"1","(2500,3775)","0","standard","I162";
;
CDS_LIB"standard"
BODY_TYPE"PLUMBING"
HDL_TAP"TRUE";
"B \NAC \NWC"19;
"S \NAC"
BN"3"36;
%"TAP"
"1","(2500,3975)","0","standard","I163";
;
CDS_LIB"standard"
BODY_TYPE"PLUMBING"
HDL_TAP"TRUE";
"B \NAC \NWC"19;
"S \NAC"
BN"5"34;
%"TAP"
"1","(2500,4075)","0","standard","I164";
;
CDS_LIB"standard"
BODY_TYPE"PLUMBING"
HDL_TAP"TRUE";
"B \NAC \NWC"19;
"S \NAC"
BN"6"33;
%"TAP"
"1","(2500,4175)","0","standard","I165";
;
CDS_LIB"standard"
BODY_TYPE"PLUMBING"
HDL_TAP"TRUE";
"B \NAC \NWC"19;
"S \NAC"
BN"7"32;
%"TAP"
"1","(2500,4275)","0","standard","I166";
;
CDS_LIB"standard"
BODY_TYPE"PLUMBING"
HDL_TAP"TRUE";
"B \NAC \NWC"19;
"S \NAC"
BN"8"31;
%"TAP"
"1","(2500,4375)","0","standard","I167";
;
CDS_LIB"standard"
BODY_TYPE"PLUMBING"
HDL_TAP"TRUE";
"B \NAC \NWC"19;
"S \NAC"
BN"9"30;
%"TAP"
"1","(2325,4425)","0","standard","I172";
;
CDS_LIB"standard"
BODY_TYPE"PLUMBING"
HDL_TAP"TRUE";
"B \NAC \NWC"17;
"S \NAC"
BN"9"53;
%"UNIVERSAL_GND"
"1","(4000,725)","0","logical_power","I174";
;
CDS_LIB"logical_power"
HDL_POWER"GND";
"A"6;
%"SCONN288_ADR50017P087CC"
"3","(4850,2800)","0","pure_quanta","I175";
;
PART_NUMBER"DFHST8FS460"
MATERIAL"IO"
PART_TYPE"SMLF"
VALUE"SCONN288_ADR50017-P087CC"
$LOCATION"J12"
NEEDS_NO_SIZE"TRUE"
CDS_LMAN_SYM_OUTLINE"-450,1775,450,-1775"
CDS_LIB"pure_quanta"
CDS_LOCATION"J12"
$SEC"3"
CDS_SEC"3";
"G3"
$PN"G3"5;
"G2"
$PN"G2"5;
"G1"
$PN"G1"5;
"VSS62"
$PN"141"5;
"VSS61"
$PN"139"5;
"VSS60"
$PN"136"5;
"VSS58"
$PN"132"5;
"VSS104"
$PN"240"6;
"VSS102"
$PN"235"6;
"VSS100"
$PN"230"6;
"VIN_BULK2"
$PN"146"2;
"VIN_BULK1"
$PN"145"2;
"VIN_BULK0"
$PN"1"2;
"VSS126"
$PN"288"6;
"VSS125"
$PN"286"6;
"VSS124"
$PN"284"6;
"VSS123"
$PN"281"6;
"VSS122"
$PN"279"6;
"VSS121"
$PN"277"6;
"VSS120"
$PN"275"6;
"VSS119"
$PN"273"6;
"VSS118"
$PN"270"6;
"VSS117"
$PN"268"6;
"VSS116"
$PN"266"6;
"VSS115"
$PN"264"6;
"VSS114"
$PN"262"6;
"VSS113"
$PN"259"6;
"VSS112"
$PN"257"6;
"VSS111"
$PN"255"6;
"VSS110"
$PN"253"6;
"VSS109"
$PN"251"6;
"VSS108"
$PN"248"6;
"VSS107"
$PN"246"6;
"VSS106"
$PN"244"6;
"VSS105"
$PN"242"6;
"VSS103"
$PN"237"6;
"VSS101"
$PN"233"6;
"VSS99"
$PN"228"6;
"VSS98"
$PN"226"6;
"VSS97"
$PN"224"6;
"VSS96"
$PN"222"6;
"VSS95"
$PN"219"6;
"VSS94"
$PN"216"6;
"VSS93"
$PN"214"6;
"VSS92"
$PN"212"6;
"VSS91"
$PN"210"6;
"VSS90"
$PN"208"6;
"VSS89"
$PN"206"6;
"VSS88"
$PN"204"6;
"VSS87"
$PN"202"6;
"VSS86"
$PN"199"6;
"VSS85"
$PN"197"6;
"VSS84"
$PN"195"6;
"VSS83"
$PN"193"6;
"VSS82"
$PN"191"6;
"VSS81"
$PN"188"6;
"VSS80"
$PN"186"6;
"VSS79"
$PN"184"6;
"VSS78"
$PN"182"6;
"VSS77"
$PN"180"6;
"VSS76"
$PN"177"6;
"VSS75"
$PN"175"6;
"VSS74"
$PN"173"6;
"VSS73"
$PN"171"6;
"VSS72"
$PN"169"6;
"VSS71"
$PN"166"6;
"VSS70"
$PN"164"6;
"VSS69"
$PN"162"6;
"VSS68"
$PN"160"6;
"VSS67"
$PN"158"6;
"VSS66"
$PN"155"6;
"VSS65"
$PN"153"6;
"VSS64"
$PN"151"6;
"VSS63"
$PN"143"5;
"VSS59"
$PN"134"5;
"VSS57"
$PN"130"5;
"VSS56"
$PN"128"5;
"VSS55"
$PN"125"5;
"VSS54"
$PN"123"5;
"VSS53"
$PN"121"5;
"VSS52"
$PN"119"5;
"VSS51"
$PN"117"5;
"VSS50"
$PN"114"5;
"VSS49"
$PN"112"5;
"VSS48"
$PN"110"5;
"VSS47"
$PN"108"5;
"VSS46"
$PN"106"5;
"VSS45"
$PN"103"5;
"VSS44"
$PN"101"5;
"VSS43"
$PN"99"5;
"VSS42"
$PN"97"5;
"VSS41"
$PN"95"5;
"VSS40"
$PN"92"5;
"VSS39"
$PN"90"5;
"VSS38"
$PN"88"5;
"VSS37"
$PN"85"5;
"VSS36"
$PN"83"5;
"VSS35"
$PN"81"5;
"VSS34"
$PN"79"5;
"VSS33"
$PN"77"5;
"VSS32"
$PN"75"5;
"VSS31"
$PN"73"5;
"VSS30"
$PN"71"5;
"VSS29"
$PN"69"5;
"VSS28"
$PN"67"5;
"VSS27"
$PN"65"5;
"VSS26"
$PN"63"5;
"VSS25"
$PN"61"5;
"VSS24"
$PN"59"5;
"VSS23"
$PN"57"5;
"VSS22"
$PN"54"5;
"VSS21"
$PN"52"5;
"VSS20"
$PN"50"5;
"VSS19"
$PN"48"5;
"VSS18"
$PN"46"5;
"VSS17"
$PN"43"5;
"VSS16"
$PN"41"5;
"VSS15"
$PN"39"5;
"VSS14"
$PN"37"5;
"VSS13"
$PN"35"5;
"VSS12"
$PN"32"5;
"VSS11"
$PN"30"5;
"VSS10"
$PN"28"5;
"VSS9"
$PN"26"5;
"VSS8"
$PN"24"5;
"VSS7"
$PN"21"5;
"VSS6"
$PN"19"5;
"VSS5"
$PN"17"5;
"VSS4"
$PN"15"5;
"VSS3"
$PN"13"5;
"VSS2"
$PN"10"5;
"VSS1"
$PN"8"5;
"VSS0"
$PN"6"5;
%"UNIVERSAL_GND"
"1","(5700,725)","0","logical_power","I176";
;
CDS_LIB"logical_power"
HDL_POWER"GND";
"A"5;
%"VCC_CORE"
"1","(4000,4975)","0","logical_power","I177";
;
HDL_POWER"P12V_S3_AUX_CPU0_NVDIMM"
CDS_LIB"logical_power";
"A"2;
%"SCONN288_ADR50017P087CC"
"2","(1425,3425)","0","pure_quanta","I178";
;
PART_NUMBER"DFHST8FS460"
PART_TYPE"SMLF"
MATERIAL"IO"
VALUE"SCONN288_ADR50017-P087CC"
LOCATION"J12"
NEEDS_NO_SIZE"TRUE"
CDS_LMAN_SYM_OUTLINE"-600,1150,600,-1150"
CDS_LIB"pure_quanta"
$SEC"2"
CDS_SEC"2";
"DQS7_A_C||TDQS7_A_C \B"
$PN"178"32;
"DQS6_A_T||TDQS6_A_T"
$PN"168"50;
"DQS8_B_T||TDQS8_B_T"
$PN"283"61;
"DQS8_B_C||TDQS8_B_C \B"
$PN"282"40;
"DQS7_B_T||TDQS7_B_T"
$PN"272"60;
"DQS0_A_C \B"
$PN"12"38;
"DQS0_A_T"
$PN"11"62;
"DQS0_B_C \B"
$PN"105"48;
"DQS0_B_T"
$PN"104"69;
"DQS1_A_C \B"
$PN"23"39;
"DQS1_A_T"
$PN"22"54;
"DQS1_B_C \B"
$PN"116"49;
"DQS1_B_T"
$PN"115"64;
"DQS2_A_C \B"
$PN"34"37;
"DQS2_A_T"
$PN"33"56;
"DQS2_B_C \B"
$PN"127"47;
"DQS2_B_T"
$PN"126"66;
"DQS3_A_C \B"
$PN"45"36;
"DQS3_A_T"
$PN"44"55;
"DQS3_B_C \B"
$PN"138"46;
"DQS3_B_T"
$PN"137"65;
"DQS4_A_C \B"
$PN"56"35;
"DQS4_A_T"
$PN"55"57;
"DQS4_B_C \B"
$PN"238"45;
"DQS4_B_T"
$PN"239"67;
"DQS5_A_C||TDQS5_A_C||DQS5_A_T||TDQS5_A_T \B"
$PN"156"34;
"DQS5_A_T||TDQS5_A_T"
$PN"157"58;
"DQS5_B_C||TDQS5_B_C \B"
$PN"249"44;
"DQS5_B_T||TDQS5_B_T"
$PN"250"68;
"DQS6_A_C||TDQS6_A_C||DQS6_A_T||TDQS6_A_T \B"
$PN"167"33;
"DQS6_B_C||TDQS6_B_C \B"
$PN"260"43;
"DQS6_B_T||TDQS6_B_T"
$PN"261"59;
"DQS7_A_T||TDQS7_A_T"
$PN"179"52;
"DQS7_B_C||TDQS7_B_C \B"
$PN"271"42;
"DQS8_A_C||TDQS8_A_C \B"
$PN"189"31;
"DQS8_A_T||TDQS8_A_T"
$PN"190"51;
"DQS9_A_C||TDQS9_A_C \B"
$PN"200"30;
"DQS9_A_T||TDQS9_A_T"
$PN"201"53;
"DQS9_B_C||TDQS9_B_C \B"
$PN"94"41;
"DQS9_B_T||TDQS9_B_T||DBI4_B_N"
$PN"93"63;
%"Q_RES"
"1","(-3050,1725)","0","pure_quanta","I179";
;
PART_NUMBER"CS04992FB07"
VALUE"49.9"
MATERIAL"CHIP"
$LOCATION"R3886"
CDS_LIB"pure_quanta"
PACK_TYPE"0402LF"
TOLERANCE"1%"
WATTAGE"1/16W"
CDS_LOCATION"R3886"
$SEC"1"
CDS_SEC"1";
"B"
$PN"2"25;
"A"
$PN"1"20;
%"Q_RES"
"2","(-1850,275)","0","pure_quanta","I2";
;
PART_NUMBER"CS33572FB01"
VALUE"35.7K"
TOLERANCE"1%"
MATERIAL"CHIP"
WATTAGE"1/16W"
PACK_TYPE"0402LF"
$LOCATION"R37"
CDS_LIB"pure_quanta"
CDS_LOCATION"R37"
$SEC"1"
CDS_SEC"1";
"A"
$PN"1"178;
"B"
$PN"2"9;
%"SCONN288_ADR50017P087CC"
"1","(-1250,2700)","0","pure_quanta","I24";
;
PART_NUMBER"DFHST8FS460"
PART_TYPE"SMLF"
MATERIAL"IO"
VALUE"SCONN288_ADR50017-P087CC"
$LOCATION"J12"
NEEDS_NO_SIZE"TRUE"
CDS_LMAN_SYM_OUTLINE"-450,1875,450,-1875"
CDS_LIB"pure_quanta"
CDS_LOCATION"J12"
$SEC"1"
CDS_SEC"1";
"DQ31_A"
$PN"194"70;
"CB7_A"
$PN"205"177;
"CB4_A"
$PN"58"176;
"CB1_A"
$PN"53"73;
"CB7_B"
$PN"236"175;
"ALERT_N \B"
$PN"62"22;
"CA0_A"
$PN"66"174;
"CA0_B"
$PN"76"173;
"CA1_A"
$PN"211"172;
"CA1_B"
$PN"221"171;
"CA2_A"
$PN"68"170;
"CA2_B"
$PN"78"169;
"CA3_A"
$PN"213"168;
"CA3_B"
$PN"223"167;
"CA4_A"
$PN"70"166;
"CA4_B"
$PN"80"165;
"CA5_A"
$PN"215"164;
"CA5_B"
$PN"225"163;
"CA6_A"
$PN"72"162;
"CA6_B"
$PN"82"161;
"CB6_A"
$PN"203"160;
"CB5_A"
$PN"60"159;
"CB3_A"
$PN"198"158;
"CB2_A"
$PN"196"157;
"CB0_A"
$PN"51"156;
"CB6_B"
$PN"234"155;
"CB5_B"
$PN"91"154;
"CB4_B"
$PN"89"153;
"CB3_B"
$PN"243"152;
"CB2_B"
$PN"241"151;
"CB1_B"
$PN"98"150;
"CB0_B"
$PN"96"149;
"CK_C \B"
$PN"218"148;
"CK_T"
$PN"217"147;
"CS0_A_N"
$PN"64"146;
"CS0_B_N"
$PN"84"145;
"CS1_A_N"
$PN"209"144;
"CS1_B_N"
$PN"229"143;
"DQ30_A"
$PN"192"71;
"DQ29_A"
$PN"49"142;
"DQ28_A"
$PN"47"141;
"DQ27_A"
$PN"187"140;
"DQ26_A"
$PN"185"139;
"DQ25_A"
$PN"42"138;
"DQ24_A"
$PN"40"137;
"DQ23_A"
$PN"183"136;
"DQ22_A"
$PN"181"135;
"DQ21_A"
$PN"38"134;
"DQ20_A"
$PN"36"133;
"DQ19_A"
$PN"176"132;
"DQ18_A"
$PN"174"131;
"DQ17_A"
$PN"31"130;
"DQ16_A"
$PN"29"129;
"DQ15_A"
$PN"172"128;
"DQ14_A"
$PN"170"127;
"DQ13_A"
$PN"27"126;
"DQ12_A"
$PN"25"125;
"DQ11_A"
$PN"165"124;
"DQ10_A"
$PN"163"123;
"DQ9_A"
$PN"20"122;
"DQ8_A"
$PN"18"75;
"DQ7_A"
$PN"161"76;
"DQ6_A"
$PN"159"121;
"DQ5_A"
$PN"16"120;
"DQ4_A"
$PN"14"119;
"DQ3_A"
$PN"154"118;
"DQ2_A"
$PN"152"117;
"DQ1_A"
$PN"9"116;
"DQ0_A"
$PN"7"115;
"DQ31_B"
$PN"287"72;
"DQ30_B"
$PN"285"114;
"DQ29_B"
$PN"142"113;
"DQ28_B"
$PN"140"112;
"DQ27_B"
$PN"280"111;
"DQ26_B"
$PN"278"29;
"DQ25_B"
$PN"135"110;
"DQ24_B"
$PN"133"109;
"DQ23_B"
$PN"276"108;
"DQ22_B"
$PN"274"107;
"DQ21_B"
$PN"131"106;
"DQ20_B"
$PN"129"105;
"DQ19_B"
$PN"269"104;
"DQ18_B"
$PN"267"103;
"DQ17_B"
$PN"124"102;
"DQ16_B"
$PN"122"101;
"DQ15_B"
$PN"265"100;
"DQ14_B"
$PN"263"99;
"DQ13_B"
$PN"120"98;
"DQ12_B"
$PN"118"97;
"DQ11_B"
$PN"258"96;
"DQ10_B"
$PN"256"74;
"DQ9_B"
$PN"113"95;
"DQ8_B"
$PN"111"94;
"DQ7_B"
$PN"254"93;
"DQ6_B"
$PN"252"92;
"DQ5_B"
$PN"109"91;
"DQ4_B"
$PN"107"90;
"DQ3_B"
$PN"247"89;
"DQ2_B"
$PN"245"88;
"DQ1_B"
$PN"102"87;
"DQ0_B"
$PN"100"86;
"HSA"
$PN"148"24;
"HSCL"
$PN"4"20;
"HSDA"
$PN"5"21;
"LBD||RSP_A_N"
$PN"86"85;
"LBS||RSP_B_N"
$PN"87"84;
"PAR_A"
$PN"74"83;
"PAR_B"
$PN"227"82;
"PWR_GOOD||FAIL_N"
$PN"147"28;
"RESET_N \B"
$PN"207"23;
"RFU6"
$PN"232"81;
"RFU5"
$PN"231"27;
"RFU4"
$PN"220"26;
"RFU3"
$PN"150"80;
"RFU2"
$PN"149"79;
"RFU1"
$PN"144"78;
"RFU0"
$PN"2"77;
"VIN_MGMT"
$PN"3"1;
%"TAP"
"1","(-2075,2225)","2","standard","I25";
;
CDS_LIB"standard"
BODY_TYPE"PLUMBING"
HDL_TAP"TRUE";
"B \NAC \NWC"11;
"S \NAC"
BN"0"149;
%"TAP"
"1","(-2075,2275)","2","standard","I26";
;
CDS_LIB"standard"
BODY_TYPE"PLUMBING"
HDL_TAP"TRUE";
"B \NAC \NWC"11;
"S \NAC"
BN"1"150;
%"TAP"
"1","(-2075,2325)","2","standard","I27";
;
CDS_LIB"standard"
BODY_TYPE"PLUMBING"
HDL_TAP"TRUE";
"B \NAC \NWC"11;
"S \NAC"
BN"2"151;
%"TAP"
"1","(-425,1225)","0","standard","I28";
;
CDS_LIB"standard"
BODY_TYPE"PLUMBING"
HDL_TAP"TRUE";
"B \NAC \NWC"15;
"S \NAC"
BN"0"86;
%"TAP"
"1","(-425,1275)","0","standard","I29";
;
CDS_LIB"standard"
BODY_TYPE"PLUMBING"
HDL_TAP"TRUE";
"B \NAC \NWC"15;
"S \NAC"
BN"1"87;
%"TAP"
"1","(-425,1425)","0","standard","I30";
;
CDS_LIB"standard"
BODY_TYPE"PLUMBING"
HDL_TAP"TRUE";
"B \NAC \NWC"15;
"S \NAC"
BN"4"90;
%"TAP"
"1","(-425,1325)","0","standard","I31";
;
CDS_LIB"standard"
BODY_TYPE"PLUMBING"
HDL_TAP"TRUE";
"B \NAC \NWC"15;
"S \NAC"
BN"2"88;
%"TAP"
"1","(-425,1375)","0","standard","I32";
;
CDS_LIB"standard"
BODY_TYPE"PLUMBING"
HDL_TAP"TRUE";
"B \NAC \NWC"15;
"S \NAC"
BN"3"89;
%"TAP"
"1","(-425,1575)","0","standard","I33";
;
CDS_LIB"standard"
BODY_TYPE"PLUMBING"
HDL_TAP"TRUE";
"B \NAC \NWC"15;
"S \NAC"
BN"7"93;
%"TAP"
"1","(-425,1525)","0","standard","I34";
;
CDS_LIB"standard"
BODY_TYPE"PLUMBING"
HDL_TAP"TRUE";
"B \NAC \NWC"15;
"S \NAC"
BN"6"92;
%"TAP"
"1","(-425,1475)","0","standard","I35";
;
CDS_LIB"standard"
BODY_TYPE"PLUMBING"
HDL_TAP"TRUE";
"B \NAC \NWC"15;
"S \NAC"
BN"5"91;
%"TAP"
"1","(-425,1825)","0","standard","I36";
;
CDS_LIB"standard"
BODY_TYPE"PLUMBING"
HDL_TAP"TRUE";
"B \NAC \NWC"15;
"S \NAC"
BN"12"97;
%"TAP"
"1","(-425,1775)","0","standard","I37";
;
CDS_LIB"standard"
BODY_TYPE"PLUMBING"
HDL_TAP"TRUE";
"B \NAC \NWC"15;
"S \NAC"
BN"11"96;
%"TAP"
"1","(-425,1725)","0","standard","I38";
;
CDS_LIB"standard"
BODY_TYPE"PLUMBING"
HDL_TAP"TRUE";
"B \NAC \NWC"15;
"S \NAC"
BN"10"74;
%"TAP"
"1","(-425,1675)","0","standard","I39";
;
CDS_LIB"standard"
BODY_TYPE"PLUMBING"
HDL_TAP"TRUE";
"B \NAC \NWC"15;
"S \NAC"
BN"9"95;
%"TAP"
"1","(-425,1625)","0","standard","I40";
;
CDS_LIB"standard"
BODY_TYPE"PLUMBING"
HDL_TAP"TRUE";
"B \NAC \NWC"15;
"S \NAC"
BN"8"94;
%"TAP"
"1","(-425,1875)","0","standard","I41";
;
CDS_LIB"standard"
BODY_TYPE"PLUMBING"
HDL_TAP"TRUE";
"B \NAC \NWC"15;
"S \NAC"
BN"13"98;
%"TAP"
"1","(-425,1925)","0","standard","I42";
;
CDS_LIB"standard"
BODY_TYPE"PLUMBING"
HDL_TAP"TRUE";
"B \NAC \NWC"15;
"S \NAC"
BN"14"99;
%"TAP"
"1","(-425,1975)","0","standard","I43";
;
CDS_LIB"standard"
BODY_TYPE"PLUMBING"
HDL_TAP"TRUE";
"B \NAC \NWC"15;
"S \NAC"
BN"15"100;
%"TAP"
"1","(-425,2025)","0","standard","I44";
;
CDS_LIB"standard"
BODY_TYPE"PLUMBING"
HDL_TAP"TRUE";
"B \NAC \NWC"15;
"S \NAC"
BN"16"101;
%"TAP"
"1","(-425,2075)","0","standard","I45";
;
CDS_LIB"standard"
BODY_TYPE"PLUMBING"
HDL_TAP"TRUE";
"B \NAC \NWC"15;
"S \NAC"
BN"17"102;
%"TAP"
"1","(-425,2325)","0","standard","I46";
;
CDS_LIB"standard"
BODY_TYPE"PLUMBING"
HDL_TAP"TRUE";
"B \NAC \NWC"15;
"S \NAC"
BN"22"107;
%"TAP"
"1","(-425,2275)","0","standard","I47";
;
CDS_LIB"standard"
BODY_TYPE"PLUMBING"
HDL_TAP"TRUE";
"B \NAC \NWC"15;
"S \NAC"
BN"21"106;
%"TAP"
"1","(-425,2225)","0","standard","I48";
;
CDS_LIB"standard"
BODY_TYPE"PLUMBING"
HDL_TAP"TRUE";
"B \NAC \NWC"15;
"S \NAC"
BN"20"105;
%"TAP"
"1","(-425,2175)","0","standard","I49";
;
CDS_LIB"standard"
BODY_TYPE"PLUMBING"
HDL_TAP"TRUE";
"B \NAC \NWC"15;
"S \NAC"
BN"19"104;
%"TAP"
"1","(-425,2125)","0","standard","I50";
;
CDS_LIB"standard"
BODY_TYPE"PLUMBING"
HDL_TAP"TRUE";
"B \NAC \NWC"15;
"S \NAC"
BN"18"103;
%"TAP"
"1","(-2075,2375)","2","standard","I51";
;
CDS_LIB"standard"
BODY_TYPE"PLUMBING"
HDL_TAP"TRUE";
"B \NAC \NWC"11;
"S \NAC"
BN"3"152;
%"TAP"
"1","(-2075,2425)","2","standard","I52";
;
CDS_LIB"standard"
BODY_TYPE"PLUMBING"
HDL_TAP"TRUE";
"B \NAC \NWC"11;
"S \NAC"
BN"4"153;
%"TAP"
"1","(-2075,2475)","2","standard","I53";
;
CDS_LIB"standard"
BODY_TYPE"PLUMBING"
HDL_TAP"TRUE";
"B \NAC \NWC"11;
"S \NAC"
BN"5"154;
%"TAP"
"1","(-2075,2575)","2","standard","I54";
;
CDS_LIB"standard"
BODY_TYPE"PLUMBING"
HDL_TAP"TRUE";
"B \NAC \NWC"11;
"S \NAC"
BN"7"175;
%"TAP"
"1","(-2075,2525)","2","standard","I55";
;
CDS_LIB"standard"
BODY_TYPE"PLUMBING"
HDL_TAP"TRUE";
"B \NAC \NWC"11;
"S \NAC"
BN"6"155;
%"TAP"
"1","(-2075,2675)","2","standard","I56";
;
CDS_LIB"standard"
BODY_TYPE"PLUMBING"
HDL_TAP"TRUE";
"B \NAC \NWC"10;
"S \NAC"
BN"0"156;
%"TAP"
"1","(-2075,2825)","2","standard","I57";
;
CDS_LIB"standard"
BODY_TYPE"PLUMBING"
HDL_TAP"TRUE";
"B \NAC \NWC"10;
"S \NAC"
BN"3"158;
%"TAP"
"1","(-2075,2775)","2","standard","I58";
;
CDS_LIB"standard"
BODY_TYPE"PLUMBING"
HDL_TAP"TRUE";
"B \NAC \NWC"10;
"S \NAC"
BN"2"157;
%"TAP"
"1","(-2075,2725)","2","standard","I59";
;
CDS_LIB"standard"
BODY_TYPE"PLUMBING"
HDL_TAP"TRUE";
"B \NAC \NWC"10;
"S \NAC"
BN"1"73;
%"TAP"
"1","(-2075,2925)","2","standard","I60";
;
CDS_LIB"standard"
BODY_TYPE"PLUMBING"
HDL_TAP"TRUE";
"B \NAC \NWC"10;
"S \NAC"
BN"5"159;
%"TAP"
"1","(-2075,3025)","2","standard","I61";
;
CDS_LIB"standard"
BODY_TYPE"PLUMBING"
HDL_TAP"TRUE";
"B \NAC \NWC"10;
"S \NAC"
BN"7"177;
%"TAP"
"1","(-2075,2975)","2","standard","I62";
;
CDS_LIB"standard"
BODY_TYPE"PLUMBING"
HDL_TAP"TRUE";
"B \NAC \NWC"10;
"S \NAC"
BN"6"160;
%"TAP"
"1","(-2075,2875)","2","standard","I63";
;
CDS_LIB"standard"
BODY_TYPE"PLUMBING"
HDL_TAP"TRUE";
"B \NAC \NWC"10;
"S \NAC"
BN"4"176;
%"TAP"
"1","(-2075,3825)","2","standard","I64";
;
CDS_LIB"standard"
BODY_TYPE"PLUMBING"
HDL_TAP"TRUE";
"B \NAC \NWC"13;
"S \NAC"
BN"2"169;
%"TAP"
"1","(-2075,3775)","2","standard","I65";
;
CDS_LIB"standard"
BODY_TYPE"PLUMBING"
HDL_TAP"TRUE";
"B \NAC \NWC"13;
"S \NAC"
BN"1"171;
%"TAP"
"1","(-2075,3725)","2","standard","I66";
;
CDS_LIB"standard"
BODY_TYPE"PLUMBING"
HDL_TAP"TRUE";
"B \NAC \NWC"13;
"S \NAC"
BN"0"173;
%"TAP"
"1","(-2075,3875)","2","standard","I67";
;
CDS_LIB"standard"
BODY_TYPE"PLUMBING"
HDL_TAP"TRUE";
"B \NAC \NWC"13;
"S \NAC"
BN"3"167;
%"TAP"
"1","(-2075,4025)","2","standard","I68";
;
CDS_LIB"standard"
BODY_TYPE"PLUMBING"
HDL_TAP"TRUE";
"B \NAC \NWC"13;
"S \NAC"
BN"6"161;
%"TAP"
"1","(-2075,3975)","2","standard","I69";
;
CDS_LIB"standard"
BODY_TYPE"PLUMBING"
HDL_TAP"TRUE";
"B \NAC \NWC"13;
"S \NAC"
BN"5"163;
%"TAP"
"1","(-2075,3925)","2","standard","I70";
;
CDS_LIB"standard"
BODY_TYPE"PLUMBING"
HDL_TAP"TRUE";
"B \NAC \NWC"13;
"S \NAC"
BN"4"165;
%"TAP"
"1","(-2075,4125)","2","standard","I71";
;
CDS_LIB"standard"
BODY_TYPE"PLUMBING"
HDL_TAP"TRUE";
"B \NAC \NWC"12;
"S \NAC"
BN"0"174;
%"TAP"
"1","(-2075,4175)","2","standard","I72";
;
CDS_LIB"standard"
BODY_TYPE"PLUMBING"
HDL_TAP"TRUE";
"B \NAC \NWC"12;
"S \NAC"
BN"1"172;
%"TAP"
"1","(-2075,4225)","2","standard","I73";
;
CDS_LIB"standard"
BODY_TYPE"PLUMBING"
HDL_TAP"TRUE";
"B \NAC \NWC"12;
"S \NAC"
BN"2"170;
%"TAP"
"1","(-2075,4325)","2","standard","I74";
;
CDS_LIB"standard"
BODY_TYPE"PLUMBING"
HDL_TAP"TRUE";
"B \NAC \NWC"12;
"S \NAC"
BN"4"166;
%"TAP"
"1","(-2075,4275)","2","standard","I75";
;
CDS_LIB"standard"
BODY_TYPE"PLUMBING"
HDL_TAP"TRUE";
"B \NAC \NWC"12;
"S \NAC"
BN"3"168;
%"TAP"
"1","(-2075,4375)","2","standard","I76";
;
CDS_LIB"standard"
BODY_TYPE"PLUMBING"
HDL_TAP"TRUE";
"B \NAC \NWC"12;
"S \NAC"
BN"5"164;
%"TAP"
"1","(-425,2375)","0","standard","I77";
;
CDS_LIB"standard"
BODY_TYPE"PLUMBING"
HDL_TAP"TRUE";
"B \NAC \NWC"15;
"S \NAC"
BN"23"108;
%"TAP"
"1","(-425,2575)","0","standard","I78";
;
CDS_LIB"standard"
BODY_TYPE"PLUMBING"
HDL_TAP"TRUE";
"B \NAC \NWC"15;
"S \NAC"
BN"27"111;
%"TAP"
"1","(-425,2475)","0","standard","I79";
;
CDS_LIB"standard"
BODY_TYPE"PLUMBING"
HDL_TAP"TRUE";
"B \NAC \NWC"15;
"S \NAC"
BN"25"110;
%"TAP"
"1","(-425,2525)","0","standard","I80";
;
CDS_LIB"standard"
BODY_TYPE"PLUMBING"
HDL_TAP"TRUE";
"B \NAC \NWC"15;
"S \NAC"
BN"26"29;
%"TAP"
"1","(-425,2425)","0","standard","I81";
;
CDS_LIB"standard"
BODY_TYPE"PLUMBING"
HDL_TAP"TRUE";
"B \NAC \NWC"15;
"S \NAC"
BN"24"109;
%"TAP"
"1","(-425,2775)","0","standard","I82";
;
CDS_LIB"standard"
BODY_TYPE"PLUMBING"
HDL_TAP"TRUE";
"B \NAC \NWC"15;
"S \NAC"
BN"31"72;
%"TAP"
"1","(-425,2725)","0","standard","I83";
;
CDS_LIB"standard"
BODY_TYPE"PLUMBING"
HDL_TAP"TRUE";
"B \NAC \NWC"15;
"S \NAC"
BN"30"114;
%"TAP"
"1","(-425,2675)","0","standard","I84";
;
CDS_LIB"standard"
BODY_TYPE"PLUMBING"
HDL_TAP"TRUE";
"B \NAC \NWC"15;
"S \NAC"
BN"29"113;
%"TAP"
"1","(-425,2625)","0","standard","I85";
;
CDS_LIB"standard"
BODY_TYPE"PLUMBING"
HDL_TAP"TRUE";
"B \NAC \NWC"15;
"S \NAC"
BN"28"112;
%"TAP"
"1","(-425,2875)","0","standard","I86";
;
CDS_LIB"standard"
BODY_TYPE"PLUMBING"
HDL_TAP"TRUE";
"B \NAC \NWC"14;
"S \NAC"
BN"0"115;
%"TAP"
"1","(-425,2975)","0","standard","I87";
;
CDS_LIB"standard"
BODY_TYPE"PLUMBING"
HDL_TAP"TRUE";
"B \NAC \NWC"14;
"S \NAC"
BN"2"117;
%"TAP"
"1","(-425,2925)","0","standard","I88";
;
CDS_LIB"standard"
BODY_TYPE"PLUMBING"
HDL_TAP"TRUE";
"B \NAC \NWC"14;
"S \NAC"
BN"1"116;
%"TAP"
"1","(-425,3075)","0","standard","I89";
;
CDS_LIB"standard"
BODY_TYPE"PLUMBING"
HDL_TAP"TRUE";
"B \NAC \NWC"14;
"S \NAC"
BN"4"119;
%"TAP"
"1","(-425,3025)","0","standard","I90";
;
CDS_LIB"standard"
BODY_TYPE"PLUMBING"
HDL_TAP"TRUE";
"B \NAC \NWC"14;
"S \NAC"
BN"3"118;
%"TAP"
"1","(-425,3325)","0","standard","I91";
;
CDS_LIB"standard"
BODY_TYPE"PLUMBING"
HDL_TAP"TRUE";
"B \NAC \NWC"14;
"S \NAC"
BN"9"122;
%"TAP"
"1","(-425,3175)","0","standard","I92";
;
CDS_LIB"standard"
BODY_TYPE"PLUMBING"
HDL_TAP"TRUE";
"B \NAC \NWC"14;
"S \NAC"
BN"6"121;
%"TAP"
"1","(-425,3275)","0","standard","I93";
;
CDS_LIB"standard"
BODY_TYPE"PLUMBING"
HDL_TAP"TRUE";
"B \NAC \NWC"14;
"S \NAC"
BN"8"75;
%"TAP"
"1","(-425,3225)","0","standard","I94";
;
CDS_LIB"standard"
BODY_TYPE"PLUMBING"
HDL_TAP"TRUE";
"B \NAC \NWC"14;
"S \NAC"
BN"7"76;
%"TAP"
"1","(-425,3125)","0","standard","I95";
;
CDS_LIB"standard"
BODY_TYPE"PLUMBING"
HDL_TAP"TRUE";
"B \NAC \NWC"14;
"S \NAC"
BN"5"120;
%"TAP"
"1","(-425,3375)","0","standard","I96";
;
CDS_LIB"standard"
BODY_TYPE"PLUMBING"
HDL_TAP"TRUE";
"B \NAC \NWC"14;
"S \NAC"
BN"10"123;
%"TAP"
"1","(-425,3425)","0","standard","I97";
;
CDS_LIB"standard"
BODY_TYPE"PLUMBING"
HDL_TAP"TRUE";
"B \NAC \NWC"14;
"S \NAC"
BN"11"124;
%"TAP"
"1","(-425,3475)","0","standard","I98";
;
CDS_LIB"standard"
BODY_TYPE"PLUMBING"
HDL_TAP"TRUE";
"B \NAC \NWC"14;
"S \NAC"
BN"12"125;
%"TAP"
"1","(-425,3625)","0","standard","I99";
;
CDS_LIB"standard"
BODY_TYPE"PLUMBING"
HDL_TAP"TRUE";
"B \NAC \NWC"14;
"S \NAC"
BN"15"128;
END.
